(kicad_pcb
	(version 20260206)
	(generator "pcbnew")
	(generator_version "10.0")
	(general
		(thickness 1.6)
		(legacy_teardrops no)
	)
	(paper "A4")
	(title_block
		(title "03242023_DA0F0TMBIJ0_F0T_Motherboard_J_brd_V01_OCP.brd")
		(comment 1 "Grand Teton / footprints 2189-2193 of 6105")
	)
	(layers
		(0 "F.Cu" signal "TOP")
		(4 "In1.Cu" signal "GND")
		(6 "In2.Cu" signal "IN1")
		(8 "In3.Cu" signal "GND1")
		(10 "In4.Cu" signal "IN2")
		(12 "In5.Cu" signal "GND2")
		(14 "In6.Cu" signal "IN3")
		(16 "In7.Cu" signal "GND3")
		(18 "In8.Cu" signal "VCC")
		(20 "In9.Cu" signal "VCC1")
		(22 "In10.Cu" signal "GND4")
		(24 "In11.Cu" signal "IN4")
		(26 "In12.Cu" signal "GND5")
		(28 "In13.Cu" signal "IN5")
		(30 "In14.Cu" signal "GND6")
		(32 "In15.Cu" signal "IN6")
		(34 "In16.Cu" signal "GND7")
		(2 "B.Cu" signal "BOTTOM")
		(9 "F.Adhes" user "F.Adhesive")
		(11 "B.Adhes" user "B.Adhesive")
		(13 "F.Paste" user "Package Geometry/Pastemask Top")
		(15 "B.Paste" user "Package Geometry/Pastemask Bottom")
		(5 "F.SilkS" user "Ref Des/Silkscreen Top")
		(7 "B.SilkS" user "Ref Des/Silkscreen Bottom")
		(1 "F.Mask" user "Board Geometry/Soldermask Top")
		(3 "B.Mask" user "Board Geometry/Soldermask Bottom")
		(17 "Dwgs.User" user "User.Drawings")
		(19 "Cmts.User" user "User.Comments")
		(21 "Eco1.User" user "User.Eco1")
		(23 "Eco2.User" user "User.Eco2")
		(25 "Edge.Cuts" user "Board Geometry/Outline")
		(27 "Margin" user)
		(31 "F.CrtYd" user "Package Geometry/Place Bound Top")
		(29 "B.CrtYd" user "Package Geometry/Place Bound Bottom")
		(35 "F.Fab" user "Ref Des/Assembly Top")
		(33 "B.Fab" user "Ref Des/Assembly Bottom")
	)
	(footprint ""
		(layer "F.Cu")
		(at 40.627554 -109.444282)
		(property "Reference" "R3685"
			(at 0 0 0)
			(layer "F.SilkS")
			(hide yes)
			(effects
				(font
					(size 1.27 1.27)
				)
			)
		)
		(property "Value" ""
			(at 0 0 0)
			(layer "F.Fab")
			(effects
				(font
					(size 1.27 1.27)
				)
			)
		)
		(duplicate_pad_numbers_are_jumpers no)
		(fp_line
			(start -0.7874 -0.4064)
			(end 0.7874 -0.4064)
			(stroke
				(width 0.1524)
				(type default)
			)
			(layer "F.SilkS")
		)
		(fp_line
			(start -0.7874 0.4064)
			(end -0.7874 -0.4064)
			(stroke
				(width 0.1524)
				(type default)
			)
			(layer "F.SilkS")
		)
		(fp_line
			(start 0.7874 -0.4064)
			(end 0.7874 0.4064)
			(stroke
				(width 0.1524)
				(type default)
			)
			(layer "F.SilkS")
		)
		(fp_line
			(start 0.7874 0.4064)
			(end -0.7874 0.4064)
			(stroke
				(width 0.1524)
				(type default)
			)
			(layer "F.SilkS")
		)
		(fp_line
			(start -0.67945 -0.305054)
			(end -0.12065 -0.305054)
			(stroke
				(width 0.1)
				(type default)
			)
			(layer "F.Fab")
		)
		(fp_line
			(start -0.67945 0.3048)
			(end -0.67945 -0.305054)
			(stroke
				(width 0.1)
				(type default)
			)
			(layer "F.Fab")
		)
		(fp_line
			(start -0.12065 -0.305054)
			(end -0.12065 -0.2794)
			(stroke
				(width 0.1)
				(type default)
			)
			(layer "F.Fab")
		)
		(fp_line
			(start -0.12065 -0.2794)
			(end 0.12065 -0.2794)
			(stroke
				(width 0.1)
				(type default)
			)
			(layer "F.Fab")
		)
		(fp_line
			(start -0.12065 0.2794)
			(end -0.12065 0.3048)
			(stroke
				(width 0.1)
				(type default)
			)
			(layer "F.Fab")
		)
		(fp_line
			(start -0.12065 0.3048)
			(end -0.67945 0.3048)
			(stroke
				(width 0.1)
				(type default)
			)
			(layer "F.Fab")
		)
		(fp_line
			(start 0.120396 0.2794)
			(end -0.12065 0.2794)
			(stroke
				(width 0.1)
				(type default)
			)
			(layer "F.Fab")
		)
		(fp_line
			(start 0.120396 0.3048)
			(end 0.120396 0.2794)
			(stroke
				(width 0.1)
				(type default)
			)
			(layer "F.Fab")
		)
		(fp_line
			(start 0.12065 -0.3048)
			(end 0.67945 -0.3048)
			(stroke
				(width 0.1)
				(type default)
			)
			(layer "F.Fab")
		)
		(fp_line
			(start 0.12065 -0.2794)
			(end 0.12065 -0.3048)
			(stroke
				(width 0.1)
				(type default)
			)
			(layer "F.Fab")
		)
		(fp_line
			(start 0.67945 -0.3048)
			(end 0.67945 0.3048)
			(stroke
				(width 0.1)
				(type default)
			)
			(layer "F.Fab")
		)
		(fp_line
			(start 0.67945 0.3048)
			(end 0.120396 0.3048)
			(stroke
				(width 0.1)
				(type default)
			)
			(layer "F.Fab")
		)
		(pad "1" smd rect
			(at -0.40005 0 180)
			(size 0.4572 0.508)
			(layers "F.Cu" "F.Mask" "F.Paste")
			(net "P5V_ADC")
		)
		(pad "2" smd rect
			(at 0.40005 0 180)
			(size 0.4572 0.508)
			(layers "F.Cu" "F.Mask" "F.Paste")
			(net "P5V_ADC_MAM")
		)
	)
	(footprint ""
		(layer "F.Cu")
		(at 211.85378 -4.699)
		(property "Reference" "J73"
			(at -4.18211 1.016 90)
			(unlocked yes)
			(layer "F.SilkS")
			(effects
				(font
					(size 0.7874 0.5842)
					(thickness 0.1524)
				)
				(justify left)
			)
		)
		(property "Value" ""
			(at 0 0 0)
			(layer "F.Fab")
			(effects
				(font
					(size 1.27 1.27)
				)
			)
		)
		(duplicate_pad_numbers_are_jumpers no)
		(fp_line
			(start -1.2192 -2.1082)
			(end 1.2192 -2.1082)
			(stroke
				(width 0.1524)
				(type default)
			)
			(layer "F.SilkS")
		)
		(fp_line
			(start -1.2192 2.1082)
			(end -1.2192 -2.1082)
			(stroke
				(width 0.1524)
				(type default)
			)
			(layer "F.SilkS")
		)
		(fp_line
			(start 1.2192 -2.1082)
			(end 1.2192 2.1082)
			(stroke
				(width 0.1524)
				(type default)
			)
			(layer "F.SilkS")
		)
		(fp_line
			(start 1.2192 2.1082)
			(end -1.2192 2.1082)
			(stroke
				(width 0.1524)
				(type default)
			)
			(layer "F.SilkS")
		)
		(pad "" np_thru_hole circle
			(at -2.8829 -1.27 270)
			(size 1.0414 1.0414)
			(drill 1.0414)
			(layers "*.Cu" "*.Mask")
			(clearance 0.381)
			(thermal_gap 0.381)
		)
		(pad "" np_thru_hole circle
			(at -2.8829 1.27 270)
			(size 1.0414 1.0414)
			(drill 1.0414)
			(layers "*.Cu" "*.Mask")
			(clearance 0.381)
			(thermal_gap 0.381)
		)
		(pad "" np_thru_hole circle
			(at 3.4671 -1.27 270)
			(size 1.0414 1.0414)
			(drill 1.0414)
			(layers "*.Cu" "*.Mask")
			(clearance 0.381)
			(thermal_gap 0.381)
		)
		(pad "" np_thru_hole circle
			(at 3.4671 1.27 270)
			(size 1.0414 1.0414)
			(drill 1.0414)
			(layers "*.Cu" "*.Mask")
			(clearance 0.381)
			(thermal_gap 0.381)
		)
		(pad "1" smd rect
			(at 0.8255 -0.249936 270)
			(size 0.3048 0.508)
			(layers "F.Cu" "F.Mask" "F.Paste")
			(net "DELTA_L_85_5INCH_IN3_DN")
		)
		(pad "2" smd rect
			(at 0.8255 0.249936 270)
			(size 0.3048 0.508)
			(layers "F.Cu" "F.Mask" "F.Paste")
			(net "DELTA_L_85_5INCH_IN3_DP")
		)
		(pad "3" smd circle
			(at 0 0)
			(size 0 0)
			(layers "F.Cu" "F.Mask" "F.Paste")
			(net "DELTA_L_GND_1")
		)
		(zone
			(layer "F.Cu")
			(hatch none 0.5)
			(connect_pads
				(clearance 0)
			)
			(min_thickness 0.25)
			(keepout
				(tracks not_allowed)
				(vias allowed)
				(pads allowed)
				(copperpour not_allowed)
				(footprints allowed)
			)
			(placement
				(enabled no)
				(sheetname "")
			)
			(fill
				(thermal_gap 0.5)
				(thermal_bridge_width 0.5)
				(island_removal_mode 0)
			)
			(polygon
				(pts
					(xy 212.97138 -5.24764) (xy 212.97138 -5.152136) (xy 212.37448 -5.152136) (xy 212.37448 -4.745736)
					(xy 212.97138 -4.745736) (xy 212.97138 -4.652264) (xy 212.37448 -4.652264) (xy 212.37448 -4.245864)
					(xy 212.97138 -4.245864) (xy 212.97138 -4.15036) (xy 212.27288 -4.15036) (xy 212.27288 -5.24764)
				)
			)
		)
		(zone
			(layers "F.Cu" "B.Cu" "In1.Cu" "In2.Cu" "In3.Cu" "In4.Cu" "In5.Cu" "In6.Cu"
				"In7.Cu" "In8.Cu" "In9.Cu" "In10.Cu" "In11.Cu" "In12.Cu" "In13.Cu" "In14.Cu"
				"In15.Cu" "In16.Cu"
			)
			(hatch none 0.5)
			(connect_pads
				(clearance 0)
			)
			(min_thickness 0.25)
			(keepout
				(tracks not_allowed)
				(vias allowed)
				(pads allowed)
				(copperpour not_allowed)
				(footprints allowed)
			)
			(placement
				(enabled no)
				(sheetname "")
			)
			(fill
				(thermal_gap 0.5)
				(thermal_bridge_width 0.5)
				(island_removal_mode 0)
			)
			(polygon
				(pts
					(arc
						(start 209.89798 -5.969)
						(mid 208.04378 -5.969)
						(end 209.89798 -5.969)
					)
				)
			)
		)
		(zone
			(layers "F.Cu" "B.Cu" "In1.Cu" "In2.Cu" "In3.Cu" "In4.Cu" "In5.Cu" "In6.Cu"
				"In7.Cu" "In8.Cu" "In9.Cu" "In10.Cu" "In11.Cu" "In12.Cu" "In13.Cu" "In14.Cu"
				"In15.Cu" "In16.Cu"
			)
			(hatch none 0.5)
			(connect_pads
				(clearance 0)
			)
			(min_thickness 0.25)
			(keepout
				(tracks not_allowed)
				(vias allowed)
				(pads allowed)
				(copperpour not_allowed)
				(footprints allowed)
			)
			(placement
				(enabled no)
				(sheetname "")
			)
			(fill
				(thermal_gap 0.5)
				(thermal_bridge_width 0.5)
				(island_removal_mode 0)
			)
			(polygon
				(pts
					(arc
						(start 209.89798 -3.429)
						(mid 208.04378 -3.429)
						(end 209.89798 -3.429)
					)
				)
			)
		)
		(zone
			(layers "F.Cu" "B.Cu" "In1.Cu" "In2.Cu" "In3.Cu" "In4.Cu" "In5.Cu" "In6.Cu"
				"In7.Cu" "In8.Cu" "In9.Cu" "In10.Cu" "In11.Cu" "In12.Cu" "In13.Cu" "In14.Cu"
				"In15.Cu" "In16.Cu"
			)
			(hatch none 0.5)
			(connect_pads
				(clearance 0)
			)
			(min_thickness 0.25)
			(keepout
				(tracks not_allowed)
				(vias allowed)
				(pads allowed)
				(copperpour not_allowed)
				(footprints allowed)
			)
			(placement
				(enabled no)
				(sheetname "")
			)
			(fill
				(thermal_gap 0.5)
				(thermal_bridge_width 0.5)
				(island_removal_mode 0)
			)
			(polygon
				(pts
					(arc
						(start 216.24798 -5.969)
						(mid 214.39378 -5.969)
						(end 216.24798 -5.969)
					)
				)
			)
		)
		(zone
			(layers "F.Cu" "B.Cu" "In1.Cu" "In2.Cu" "In3.Cu" "In4.Cu" "In5.Cu" "In6.Cu"
				"In7.Cu" "In8.Cu" "In9.Cu" "In10.Cu" "In11.Cu" "In12.Cu" "In13.Cu" "In14.Cu"
				"In15.Cu" "In16.Cu"
			)
			(hatch none 0.5)
			(connect_pads
				(clearance 0)
			)
			(min_thickness 0.25)
			(keepout
				(tracks not_allowed)
				(vias allowed)
				(pads allowed)
				(copperpour not_allowed)
				(footprints allowed)
			)
			(placement
				(enabled no)
				(sheetname "")
			)
			(fill
				(thermal_gap 0.5)
				(thermal_bridge_width 0.5)
				(island_removal_mode 0)
			)
			(polygon
				(pts
					(arc
						(start 216.24798 -3.429)
						(mid 214.39378 -3.429)
						(end 216.24798 -3.429)
					)
				)
			)
		)
	)
	(footprint ""
		(layer "F.Cu")
		(at 361.36072 -402.9456 90)
		(property "Reference" "R3063"
			(at 0 0 90)
			(layer "F.SilkS")
			(hide yes)
			(effects
				(font
					(size 1.27 1.27)
				)
			)
		)
		(property "Value" ""
			(at 0 0 90)
			(layer "F.Fab")
			(effects
				(font
					(size 1.27 1.27)
				)
			)
		)
		(duplicate_pad_numbers_are_jumpers no)
		(fp_line
			(start 0.7874 -0.4064)
			(end 0.7874 0.4064)
			(stroke
				(width 0.1524)
				(type default)
			)
			(layer "F.SilkS")
		)
		(fp_line
			(start -0.7874 -0.4064)
			(end 0.7874 -0.4064)
			(stroke
				(width 0.1524)
				(type default)
			)
			(layer "F.SilkS")
		)
		(fp_line
			(start 0.7874 0.4064)
			(end -0.7874 0.4064)
			(stroke
				(width 0.1524)
				(type default)
			)
			(layer "F.SilkS")
		)
		(fp_line
			(start -0.7874 0.4064)
			(end -0.7874 -0.4064)
			(stroke
				(width 0.1524)
				(type default)
			)
			(layer "F.SilkS")
		)
		(fp_line
			(start -0.12065 -0.305054)
			(end -0.12065 -0.2794)
			(stroke
				(width 0.1)
				(type default)
			)
			(layer "F.Fab")
		)
		(fp_line
			(start -0.67945 -0.305054)
			(end -0.12065 -0.305054)
			(stroke
				(width 0.1)
				(type default)
			)
			(layer "F.Fab")
		)
		(fp_line
			(start 0.67945 -0.3048)
			(end 0.67945 0.3048)
			(stroke
				(width 0.1)
				(type default)
			)
			(layer "F.Fab")
		)
		(fp_line
			(start 0.12065 -0.3048)
			(end 0.67945 -0.3048)
			(stroke
				(width 0.1)
				(type default)
			)
			(layer "F.Fab")
		)
		(fp_line
			(start 0.12065 -0.2794)
			(end 0.12065 -0.3048)
			(stroke
				(width 0.1)
				(type default)
			)
			(layer "F.Fab")
		)
		(fp_line
			(start -0.12065 -0.2794)
			(end 0.12065 -0.2794)
			(stroke
				(width 0.1)
				(type default)
			)
			(layer "F.Fab")
		)
		(fp_line
			(start 0.120396 0.2794)
			(end -0.12065 0.2794)
			(stroke
				(width 0.1)
				(type default)
			)
			(layer "F.Fab")
		)
		(fp_line
			(start -0.12065 0.2794)
			(end -0.12065 0.3048)
			(stroke
				(width 0.1)
				(type default)
			)
			(layer "F.Fab")
		)
		(fp_line
			(start 0.67945 0.3048)
			(end 0.120396 0.3048)
			(stroke
				(width 0.1)
				(type default)
			)
			(layer "F.Fab")
		)
		(fp_line
			(start 0.120396 0.3048)
			(end 0.120396 0.2794)
			(stroke
				(width 0.1)
				(type default)
			)
			(layer "F.Fab")
		)
		(fp_line
			(start -0.12065 0.3048)
			(end -0.67945 0.3048)
			(stroke
				(width 0.1)
				(type default)
			)
			(layer "F.Fab")
		)
		(fp_line
			(start -0.67945 0.3048)
			(end -0.67945 -0.305054)
			(stroke
				(width 0.1)
				(type default)
			)
			(layer "F.Fab")
		)
		(pad "1" smd circle
			(at -0.40005 0 90)
			(size 0 0)
			(layers "F.Cu" "F.Mask" "F.Paste")
			(net "FM_PDB_BUF_EN_R")
		)
		(pad "2" smd circle
			(at 0.40005 0 90)
			(size 0 0)
			(layers "F.Cu" "F.Mask" "F.Paste")
			(net "FM_UART_EN")
		)
	)
	(footprint ""
		(layer "F.Cu")
		(at 416.919664 -366.691164 90)
		(property "Reference" "PR1780"
			(at 0 0 90)
			(layer "F.SilkS")
			(hide yes)
			(effects
				(font
					(size 1.27 1.27)
				)
			)
		)
		(property "Value" ""
			(at 0 0 90)
			(layer "F.Fab")
			(effects
				(font
					(size 1.27 1.27)
				)
			)
		)
		(duplicate_pad_numbers_are_jumpers no)
		(fp_line
			(start 0.7874 -0.4064)
			(end 0.7874 0.4064)
			(stroke
				(width 0.1524)
				(type default)
			)
			(layer "F.SilkS")
		)
		(fp_line
			(start -0.7874 -0.4064)
			(end 0.7874 -0.4064)
			(stroke
				(width 0.1524)
				(type default)
			)
			(layer "F.SilkS")
		)
		(fp_line
			(start 0.7874 0.4064)
			(end -0.7874 0.4064)
			(stroke
				(width 0.1524)
				(type default)
			)
			(layer "F.SilkS")
		)
		(fp_line
			(start -0.7874 0.4064)
			(end -0.7874 -0.4064)
			(stroke
				(width 0.1524)
				(type default)
			)
			(layer "F.SilkS")
		)
		(fp_line
			(start -0.12065 -0.305054)
			(end -0.12065 -0.2794)
			(stroke
				(width 0.1)
				(type default)
			)
			(layer "F.Fab")
		)
		(fp_line
			(start -0.67945 -0.305054)
			(end -0.12065 -0.305054)
			(stroke
				(width 0.1)
				(type default)
			)
			(layer "F.Fab")
		)
		(fp_line
			(start 0.67945 -0.3048)
			(end 0.67945 0.3048)
			(stroke
				(width 0.1)
				(type default)
			)
			(layer "F.Fab")
		)
		(fp_line
			(start 0.12065 -0.3048)
			(end 0.67945 -0.3048)
			(stroke
				(width 0.1)
				(type default)
			)
			(layer "F.Fab")
		)
		(fp_line
			(start 0.12065 -0.2794)
			(end 0.12065 -0.3048)
			(stroke
				(width 0.1)
				(type default)
			)
			(layer "F.Fab")
		)
		(fp_line
			(start -0.12065 -0.2794)
			(end 0.12065 -0.2794)
			(stroke
				(width 0.1)
				(type default)
			)
			(layer "F.Fab")
		)
		(fp_line
			(start 0.120396 0.2794)
			(end -0.12065 0.2794)
			(stroke
				(width 0.1)
				(type default)
			)
			(layer "F.Fab")
		)
		(fp_line
			(start -0.12065 0.2794)
			(end -0.12065 0.3048)
			(stroke
				(width 0.1)
				(type default)
			)
			(layer "F.Fab")
		)
		(fp_line
			(start 0.67945 0.3048)
			(end 0.120396 0.3048)
			(stroke
				(width 0.1)
				(type default)
			)
			(layer "F.Fab")
		)
		(fp_line
			(start 0.120396 0.3048)
			(end 0.120396 0.2794)
			(stroke
				(width 0.1)
				(type default)
			)
			(layer "F.Fab")
		)
		(fp_line
			(start -0.12065 0.3048)
			(end -0.67945 0.3048)
			(stroke
				(width 0.1)
				(type default)
			)
			(layer "F.Fab")
		)
		(fp_line
			(start -0.67945 0.3048)
			(end -0.67945 -0.305054)
			(stroke
				(width 0.1)
				(type default)
			)
			(layer "F.Fab")
		)
		(pad "1" smd circle
			(at -0.40005 0 90)
			(size 0 0)
			(layers "F.Cu" "F.Mask" "F.Paste")
			(net "SW_PVCCFA_EHV_FIVRA_CPU0_BOOT1")
		)
		(pad "2" smd circle
			(at 0.40005 0 90)
			(size 0 0)
			(layers "F.Cu" "F.Mask" "F.Paste")
			(net "SW_PVCCFA_EHV_FIVRA_CPU0_BOOT1_")
		)
	)
	(footprint ""
		(layer "F.Cu")
		(at 164.247576 -35.737546 180)
		(property "Reference" "R4448"
			(at 0 0 180)
			(layer "F.SilkS")
			(hide yes)
			(effects
				(font
					(size 1.27 1.27)
				)
			)
		)
		(property "Value" ""
			(at 0 0 180)
			(layer "F.Fab")
			(effects
				(font
					(size 1.27 1.27)
				)
			)
		)
		(duplicate_pad_numbers_are_jumpers no)
		(fp_line
			(start 0.7874 0.4064)
			(end -0.7874 0.4064)
			(stroke
				(width 0.1524)
				(type default)
			)
			(layer "F.SilkS")
		)
		(fp_line
			(start 0.7874 -0.4064)
			(end 0.7874 0.4064)
			(stroke
				(width 0.1524)
				(type default)
			)
			(layer "F.SilkS")
		)
		(fp_line
			(start -0.7874 0.4064)
			(end -0.7874 -0.4064)
			(stroke
				(width 0.1524)
				(type default)
			)
			(layer "F.SilkS")
		)
		(fp_line
			(start -0.7874 -0.4064)
			(end 0.7874 -0.4064)
			(stroke
				(width 0.1524)
				(type default)
			)
			(layer "F.SilkS")
		)
		(fp_line
			(start 0.67945 0.3048)
			(end 0.120396 0.3048)
			(stroke
				(width 0.1)
				(type default)
			)
			(layer "F.Fab")
		)
		(fp_line
			(start 0.67945 -0.3048)
			(end 0.67945 0.3048)
			(stroke
				(width 0.1)
				(type default)
			)
			(layer "F.Fab")
		)
		(fp_line
			(start 0.12065 -0.2794)
			(end 0.12065 -0.3048)
			(stroke
				(width 0.1)
				(type default)
			)
			(layer "F.Fab")
		)
		(fp_line
			(start 0.12065 -0.3048)
			(end 0.67945 -0.3048)
			(stroke
				(width 0.1)
				(type default)
			)
			(layer "F.Fab")
		)
		(fp_line
			(start 0.120396 0.3048)
			(end 0.120396 0.2794)
			(stroke
				(width 0.1)
				(type default)
			)
			(layer "F.Fab")
		)
		(fp_line
			(start 0.120396 0.2794)
			(end -0.12065 0.2794)
			(stroke
				(width 0.1)
				(type default)
			)
			(layer "F.Fab")
		)
		(fp_line
			(start -0.12065 0.3048)
			(end -0.67945 0.3048)
			(stroke
				(width 0.1)
				(type default)
			)
			(layer "F.Fab")
		)
		(fp_line
			(start -0.12065 0.2794)
			(end -0.12065 0.3048)
			(stroke
				(width 0.1)
				(type default)
			)
			(layer "F.Fab")
		)
		(fp_line
			(start -0.12065 -0.2794)
			(end 0.12065 -0.2794)
			(stroke
				(width 0.1)
				(type default)
			)
			(layer "F.Fab")
		)
		(fp_line
			(start -0.12065 -0.305054)
			(end -0.12065 -0.2794)
			(stroke
				(width 0.1)
				(type default)
			)
			(layer "F.Fab")
		)
		(fp_line
			(start -0.67945 0.3048)
			(end -0.67945 -0.305054)
			(stroke
				(width 0.1)
				(type default)
			)
			(layer "F.Fab")
		)
		(fp_line
			(start -0.67945 -0.305054)
			(end -0.12065 -0.305054)
			(stroke
				(width 0.1)
				(type default)
			)
			(layer "F.Fab")
		)
		(pad "1" smd circle
			(at -0.40005 0 180)
			(size 0 0)
			(layers "F.Cu" "F.Mask" "F.Paste")
			(net "P3V3_AUX")
		)
		(pad "2" smd circle
			(at 0.40005 0 180)
			(size 0 0)
			(layers "F.Cu" "F.Mask" "F.Paste")
			(net "USB_HUB_2_PSELF")
		)
	)
)
